(kicad_pcb
	(version 20260206)
	(generator "pcbnew")
	(generator_version "10.0")
	(general
		(thickness 1.6)
		(legacy_teardrops no)
	)
	(paper "A4")
	(title_block
		(title "01162023_DA0F0TEBIF0_F0T_Expander_BD_F_brd_V02_OCP.brd")
		(comment 1 "Grand Teton / footprints 1881-1887 of 9728")
	)
	(layers
		(0 "F.Cu" signal "TOP")
		(4 "In1.Cu" signal "GND")
		(6 "In2.Cu" signal "VCC")
		(8 "In3.Cu" signal "VCC1")
		(10 "In4.Cu" signal "GND1")
		(12 "In5.Cu" signal "IN1")
		(14 "In6.Cu" signal "GND2")
		(16 "In7.Cu" signal "IN2")
		(18 "In8.Cu" signal "GND3")
		(20 "In9.Cu" signal "IN3")
		(22 "In10.Cu" signal "GND4")
		(24 "In11.Cu" signal "IN4")
		(26 "In12.Cu" signal "GND5")
		(28 "In13.Cu" signal "IN5")
		(30 "In14.Cu" signal "GND6")
		(32 "In15.Cu" signal "IN6")
		(34 "In16.Cu" signal "GND7")
		(2 "B.Cu" signal "BOTTOM")
		(9 "F.Adhes" user "F.Adhesive")
		(11 "B.Adhes" user "B.Adhesive")
		(13 "F.Paste" user "Package Geometry/Pastemask Top")
		(15 "B.Paste" user "Package Geometry/Pastemask Bottom")
		(5 "F.SilkS" user "Ref Des/Silkscreen Top")
		(7 "B.SilkS" user "Ref Des/Silkscreen Bottom")
		(1 "F.Mask" user "Board Geometry/Soldermask Top")
		(3 "B.Mask" user "Board Geometry/Soldermask Bottom")
		(17 "Dwgs.User" user "User.Drawings")
		(19 "Cmts.User" user "User.Comments")
		(21 "Eco1.User" user "User.Eco1")
		(23 "Eco2.User" user "User.Eco2")
		(25 "Edge.Cuts" user "Board Geometry/Outline")
		(27 "Margin" user)
		(31 "F.CrtYd" user "Package Geometry/Place Bound Top")
		(29 "B.CrtYd" user "Package Geometry/Place Bound Bottom")
		(35 "F.Fab" user "Ref Des/Assembly Top")
		(33 "B.Fab" user "Ref Des/Assembly Bottom")
	)
	(footprint ""
		(layer "F.Cu")
		(at 264.611358 -293.245032 -90)
		(property "Reference" "R4580"
			(at 0 0 270)
			(layer "F.SilkS")
			(hide yes)
			(effects
				(font
					(size 1.27 1.27)
				)
			)
		)
		(property "Value" ""
			(at 0 0 270)
			(layer "F.Fab")
			(effects
				(font
					(size 1.27 1.27)
				)
			)
		)
		(duplicate_pad_numbers_are_jumpers no)
		(fp_line
			(start -0.7874 0.4064)
			(end -0.7874 -0.4064)
			(stroke
				(width 0.1524)
				(type default)
			)
			(layer "F.SilkS")
		)
		(fp_line
			(start 0.7874 0.4064)
			(end -0.7874 0.4064)
			(stroke
				(width 0.1524)
				(type default)
			)
			(layer "F.SilkS")
		)
		(fp_line
			(start -0.7874 -0.4064)
			(end 0.7874 -0.4064)
			(stroke
				(width 0.1524)
				(type default)
			)
			(layer "F.SilkS")
		)
		(fp_line
			(start 0.7874 -0.4064)
			(end 0.7874 0.4064)
			(stroke
				(width 0.1524)
				(type default)
			)
			(layer "F.SilkS")
		)
		(fp_line
			(start -0.67945 0.3048)
			(end -0.67945 -0.305054)
			(stroke
				(width 0.1)
				(type default)
			)
			(layer "F.Fab")
		)
		(fp_line
			(start -0.12065 0.3048)
			(end -0.67945 0.3048)
			(stroke
				(width 0.1)
				(type default)
			)
			(layer "F.Fab")
		)
		(fp_line
			(start 0.120396 0.3048)
			(end 0.120396 0.2794)
			(stroke
				(width 0.1)
				(type default)
			)
			(layer "F.Fab")
		)
		(fp_line
			(start 0.67945 0.3048)
			(end 0.120396 0.3048)
			(stroke
				(width 0.1)
				(type default)
			)
			(layer "F.Fab")
		)
		(fp_line
			(start -0.12065 0.2794)
			(end -0.12065 0.3048)
			(stroke
				(width 0.1)
				(type default)
			)
			(layer "F.Fab")
		)
		(fp_line
			(start 0.120396 0.2794)
			(end -0.12065 0.2794)
			(stroke
				(width 0.1)
				(type default)
			)
			(layer "F.Fab")
		)
		(fp_line
			(start -0.12065 -0.2794)
			(end 0.12065 -0.2794)
			(stroke
				(width 0.1)
				(type default)
			)
			(layer "F.Fab")
		)
		(fp_line
			(start 0.12065 -0.2794)
			(end 0.12065 -0.3048)
			(stroke
				(width 0.1)
				(type default)
			)
			(layer "F.Fab")
		)
		(fp_line
			(start 0.12065 -0.3048)
			(end 0.67945 -0.3048)
			(stroke
				(width 0.1)
				(type default)
			)
			(layer "F.Fab")
		)
		(fp_line
			(start 0.67945 -0.3048)
			(end 0.67945 0.3048)
			(stroke
				(width 0.1)
				(type default)
			)
			(layer "F.Fab")
		)
		(fp_line
			(start -0.67945 -0.305054)
			(end -0.12065 -0.305054)
			(stroke
				(width 0.1)
				(type default)
			)
			(layer "F.Fab")
		)
		(fp_line
			(start -0.12065 -0.305054)
			(end -0.12065 -0.2794)
			(stroke
				(width 0.1)
				(type default)
			)
			(layer "F.Fab")
		)
		(pad "1" smd circle
			(at -0.40005 0 270)
			(size 0 0)
			(layers "F.Cu" "F.Mask" "F.Paste")
			(net "PCEPLL2_VDDA18_PEX2")
		)
		(pad "2" smd circle
			(at 0.40005 0 270)
			(size 0 0)
			(layers "F.Cu" "F.Mask" "F.Paste")
			(net "PCEPLL2_VDDA18_PEX2_R")
		)
	)
	(footprint ""
		(layer "F.Cu")
		(at 268.786102 -343.952322 90)
		(property "Reference" "C2342"
			(at 0 0 90)
			(layer "F.SilkS")
			(hide yes)
			(effects
				(font
					(size 1.27 1.27)
				)
			)
		)
		(property "Value" ""
			(at 0 0 90)
			(layer "F.Fab")
			(effects
				(font
					(size 1.27 1.27)
				)
			)
		)
		(duplicate_pad_numbers_are_jumpers no)
		(fp_line
			(start 0.299974 -0.150114)
			(end 0.299974 0.150114)
			(stroke
				(width 0.1)
				(type default)
			)
			(layer "F.Fab")
		)
		(fp_line
			(start -0.299974 -0.150114)
			(end 0.299974 -0.150114)
			(stroke
				(width 0.1)
				(type default)
			)
			(layer "F.Fab")
		)
		(fp_line
			(start 0.299974 0.150114)
			(end -0.299974 0.150114)
			(stroke
				(width 0.1)
				(type default)
			)
			(layer "F.Fab")
		)
		(fp_line
			(start -0.299974 0.150114)
			(end -0.299974 -0.150114)
			(stroke
				(width 0.1)
				(type default)
			)
			(layer "F.Fab")
		)
		(pad "1" smd rect
			(at -0.2667 0 90)
			(size 0.3048 0.381)
			(layers "F.Cu" "F.Mask" "F.Paste")
			(net "P5E_PEX2_STN4_TX_DN<79>")
		)
		(pad "2" smd rect
			(at 0.2667 0 90)
			(size 0.3048 0.381)
			(layers "F.Cu" "F.Mask" "F.Paste")
			(net "P5E_PEX2_STN4_TX_C_DN<79>")
		)
	)
	(footprint ""
		(layer "F.Cu")
		(at 189.630558 -66.32194 -90)
		(property "Reference" "PC850"
			(at 0 0 270)
			(layer "F.SilkS")
			(hide yes)
			(effects
				(font
					(size 1.27 1.27)
				)
			)
		)
		(property "Value" ""
			(at 0 0 270)
			(layer "F.Fab")
			(effects
				(font
					(size 1.27 1.27)
				)
			)
		)
		(duplicate_pad_numbers_are_jumpers no)
		(fp_line
			(start -0.7874 0.4064)
			(end -0.7874 -0.4064)
			(stroke
				(width 0.1524)
				(type default)
			)
			(layer "F.SilkS")
		)
		(fp_line
			(start 0.7874 0.4064)
			(end -0.7874 0.4064)
			(stroke
				(width 0.1524)
				(type default)
			)
			(layer "F.SilkS")
		)
		(fp_line
			(start -0.7874 -0.4064)
			(end 0.7874 -0.4064)
			(stroke
				(width 0.1524)
				(type default)
			)
			(layer "F.SilkS")
		)
		(fp_line
			(start 0.7874 -0.4064)
			(end 0.7874 0.4064)
			(stroke
				(width 0.1524)
				(type default)
			)
			(layer "F.SilkS")
		)
		(fp_line
			(start -0.67945 0.3048)
			(end -0.67945 -0.305054)
			(stroke
				(width 0.1)
				(type default)
			)
			(layer "F.Fab")
		)
		(fp_line
			(start -0.12065 0.3048)
			(end -0.67945 0.3048)
			(stroke
				(width 0.1)
				(type default)
			)
			(layer "F.Fab")
		)
		(fp_line
			(start 0.120396 0.3048)
			(end 0.120396 0.2794)
			(stroke
				(width 0.1)
				(type default)
			)
			(layer "F.Fab")
		)
		(fp_line
			(start 0.67945 0.3048)
			(end 0.120396 0.3048)
			(stroke
				(width 0.1)
				(type default)
			)
			(layer "F.Fab")
		)
		(fp_line
			(start -0.12065 0.2794)
			(end -0.12065 0.3048)
			(stroke
				(width 0.1)
				(type default)
			)
			(layer "F.Fab")
		)
		(fp_line
			(start 0.120396 0.2794)
			(end -0.12065 0.2794)
			(stroke
				(width 0.1)
				(type default)
			)
			(layer "F.Fab")
		)
		(fp_line
			(start -0.12065 -0.2794)
			(end 0.12065 -0.2794)
			(stroke
				(width 0.1)
				(type default)
			)
			(layer "F.Fab")
		)
		(fp_line
			(start 0.12065 -0.2794)
			(end 0.12065 -0.3048)
			(stroke
				(width 0.1)
				(type default)
			)
			(layer "F.Fab")
		)
		(fp_line
			(start 0.12065 -0.3048)
			(end 0.67945 -0.3048)
			(stroke
				(width 0.1)
				(type default)
			)
			(layer "F.Fab")
		)
		(fp_line
			(start 0.67945 -0.3048)
			(end 0.67945 0.3048)
			(stroke
				(width 0.1)
				(type default)
			)
			(layer "F.Fab")
		)
		(fp_line
			(start -0.67945 -0.305054)
			(end -0.12065 -0.305054)
			(stroke
				(width 0.1)
				(type default)
			)
			(layer "F.Fab")
		)
		(fp_line
			(start -0.12065 -0.305054)
			(end -0.12065 -0.2794)
			(stroke
				(width 0.1)
				(type default)
			)
			(layer "F.Fab")
		)
		(pad "1" smd circle
			(at -0.40005 0 270)
			(size 0 0)
			(layers "F.Cu" "F.Mask" "F.Paste")
			(net "P12V_SSD6_CO_DV_DT")
		)
		(pad "2" smd circle
			(at 0.40005 0 270)
			(size 0 0)
			(layers "F.Cu" "F.Mask" "F.Paste")
			(net "GND")
		)
	)
	(footprint ""
		(layer "F.Cu")
		(at 338.328 -245.237 -90)
		(property "Reference" "R1790"
			(at 0 0 270)
			(layer "F.SilkS")
			(hide yes)
			(effects
				(font
					(size 1.27 1.27)
				)
			)
		)
		(property "Value" ""
			(at 0 0 270)
			(layer "F.Fab")
			(effects
				(font
					(size 1.27 1.27)
				)
			)
		)
		(duplicate_pad_numbers_are_jumpers no)
		(fp_line
			(start -0.7874 0.4064)
			(end -0.7874 -0.4064)
			(stroke
				(width 0.1524)
				(type default)
			)
			(layer "F.SilkS")
		)
		(fp_line
			(start 0.7874 0.4064)
			(end -0.7874 0.4064)
			(stroke
				(width 0.1524)
				(type default)
			)
			(layer "F.SilkS")
		)
		(fp_line
			(start -0.7874 -0.4064)
			(end 0.7874 -0.4064)
			(stroke
				(width 0.1524)
				(type default)
			)
			(layer "F.SilkS")
		)
		(fp_line
			(start 0.7874 -0.4064)
			(end 0.7874 0.4064)
			(stroke
				(width 0.1524)
				(type default)
			)
			(layer "F.SilkS")
		)
		(fp_line
			(start -0.67945 0.3048)
			(end -0.67945 -0.305054)
			(stroke
				(width 0.1)
				(type default)
			)
			(layer "F.Fab")
		)
		(fp_line
			(start -0.12065 0.3048)
			(end -0.67945 0.3048)
			(stroke
				(width 0.1)
				(type default)
			)
			(layer "F.Fab")
		)
		(fp_line
			(start 0.120396 0.3048)
			(end 0.120396 0.2794)
			(stroke
				(width 0.1)
				(type default)
			)
			(layer "F.Fab")
		)
		(fp_line
			(start 0.67945 0.3048)
			(end 0.120396 0.3048)
			(stroke
				(width 0.1)
				(type default)
			)
			(layer "F.Fab")
		)
		(fp_line
			(start -0.12065 0.2794)
			(end -0.12065 0.3048)
			(stroke
				(width 0.1)
				(type default)
			)
			(layer "F.Fab")
		)
		(fp_line
			(start 0.120396 0.2794)
			(end -0.12065 0.2794)
			(stroke
				(width 0.1)
				(type default)
			)
			(layer "F.Fab")
		)
		(fp_line
			(start -0.12065 -0.2794)
			(end 0.12065 -0.2794)
			(stroke
				(width 0.1)
				(type default)
			)
			(layer "F.Fab")
		)
		(fp_line
			(start 0.12065 -0.2794)
			(end 0.12065 -0.3048)
			(stroke
				(width 0.1)
				(type default)
			)
			(layer "F.Fab")
		)
		(fp_line
			(start 0.12065 -0.3048)
			(end 0.67945 -0.3048)
			(stroke
				(width 0.1)
				(type default)
			)
			(layer "F.Fab")
		)
		(fp_line
			(start 0.67945 -0.3048)
			(end 0.67945 0.3048)
			(stroke
				(width 0.1)
				(type default)
			)
			(layer "F.Fab")
		)
		(fp_line
			(start -0.67945 -0.305054)
			(end -0.12065 -0.305054)
			(stroke
				(width 0.1)
				(type default)
			)
			(layer "F.Fab")
		)
		(fp_line
			(start -0.12065 -0.305054)
			(end -0.12065 -0.2794)
			(stroke
				(width 0.1)
				(type default)
			)
			(layer "F.Fab")
		)
		(pad "1" smd circle
			(at -0.40005 0 270)
			(size 0 0)
			(layers "F.Cu" "F.Mask" "F.Paste")
			(net "P3V3_AUX")
		)
		(pad "2" smd circle
			(at 0.40005 0 270)
			(size 0 0)
			(layers "F.Cu" "F.Mask" "F.Paste")
			(net "RST_MB_PERST_2_N")
		)
	)
	(footprint ""
		(layer "F.Cu")
		(at 376.809 -175.16602)
		(property "Reference" "R4714"
			(at 0 0 0)
			(layer "F.SilkS")
			(hide yes)
			(effects
				(font
					(size 1.27 1.27)
				)
			)
		)
		(property "Value" ""
			(at 0 0 0)
			(layer "F.Fab")
			(effects
				(font
					(size 1.27 1.27)
				)
			)
		)
		(duplicate_pad_numbers_are_jumpers no)
		(fp_line
			(start -0.7874 -0.4064)
			(end 0.7874 -0.4064)
			(stroke
				(width 0.1524)
				(type default)
			)
			(layer "F.SilkS")
		)
		(fp_line
			(start -0.7874 0.4064)
			(end -0.7874 -0.4064)
			(stroke
				(width 0.1524)
				(type default)
			)
			(layer "F.SilkS")
		)
		(fp_line
			(start 0.7874 -0.4064)
			(end 0.7874 0.4064)
			(stroke
				(width 0.1524)
				(type default)
			)
			(layer "F.SilkS")
		)
		(fp_line
			(start 0.7874 0.4064)
			(end -0.7874 0.4064)
			(stroke
				(width 0.1524)
				(type default)
			)
			(layer "F.SilkS")
		)
		(fp_line
			(start -0.67945 -0.305054)
			(end -0.12065 -0.305054)
			(stroke
				(width 0.1)
				(type default)
			)
			(layer "F.Fab")
		)
		(fp_line
			(start -0.67945 0.3048)
			(end -0.67945 -0.305054)
			(stroke
				(width 0.1)
				(type default)
			)
			(layer "F.Fab")
		)
		(fp_line
			(start -0.12065 -0.305054)
			(end -0.12065 -0.2794)
			(stroke
				(width 0.1)
				(type default)
			)
			(layer "F.Fab")
		)
		(fp_line
			(start -0.12065 -0.2794)
			(end 0.12065 -0.2794)
			(stroke
				(width 0.1)
				(type default)
			)
			(layer "F.Fab")
		)
		(fp_line
			(start -0.12065 0.2794)
			(end -0.12065 0.3048)
			(stroke
				(width 0.1)
				(type default)
			)
			(layer "F.Fab")
		)
		(fp_line
			(start -0.12065 0.3048)
			(end -0.67945 0.3048)
			(stroke
				(width 0.1)
				(type default)
			)
			(layer "F.Fab")
		)
		(fp_line
			(start 0.120396 0.2794)
			(end -0.12065 0.2794)
			(stroke
				(width 0.1)
				(type default)
			)
			(layer "F.Fab")
		)
		(fp_line
			(start 0.120396 0.3048)
			(end 0.120396 0.2794)
			(stroke
				(width 0.1)
				(type default)
			)
			(layer "F.Fab")
		)
		(fp_line
			(start 0.12065 -0.3048)
			(end 0.67945 -0.3048)
			(stroke
				(width 0.1)
				(type default)
			)
			(layer "F.Fab")
		)
		(fp_line
			(start 0.12065 -0.2794)
			(end 0.12065 -0.3048)
			(stroke
				(width 0.1)
				(type default)
			)
			(layer "F.Fab")
		)
		(fp_line
			(start 0.67945 -0.3048)
			(end 0.67945 0.3048)
			(stroke
				(width 0.1)
				(type default)
			)
			(layer "F.Fab")
		)
		(fp_line
			(start 0.67945 0.3048)
			(end 0.120396 0.3048)
			(stroke
				(width 0.1)
				(type default)
			)
			(layer "F.Fab")
		)
		(pad "1" smd circle
			(at -0.40005 0)
			(size 0 0)
			(layers "F.Cu" "F.Mask" "F.Paste")
			(net "NIC3_PEX_PWR_EN")
		)
		(pad "2" smd circle
			(at 0.40005 0)
			(size 0 0)
			(layers "F.Cu" "F.Mask" "F.Paste")
			(net "NIC3_PEX_PWR_EN_R")
		)
	)
	(footprint ""
		(layer "F.Cu")
		(at 143.030194 -281.203908 -90)
		(property "Reference" "C3237"
			(at 0 0 270)
			(layer "F.SilkS")
			(hide yes)
			(effects
				(font
					(size 1.27 1.27)
				)
			)
		)
		(property "Value" ""
			(at 0 0 270)
			(layer "F.Fab")
			(effects
				(font
					(size 1.27 1.27)
				)
			)
		)
		(duplicate_pad_numbers_are_jumpers no)
		(fp_line
			(start -1.2954 0.5842)
			(end -1.2954 -0.5842)
			(stroke
				(width 0.1524)
				(type default)
			)
			(layer "F.SilkS")
		)
		(fp_line
			(start 1.2954 0.5842)
			(end -1.2954 0.5842)
			(stroke
				(width 0.1524)
				(type default)
			)
			(layer "F.SilkS")
		)
		(fp_line
			(start -1.2954 -0.5842)
			(end 1.2954 -0.5842)
			(stroke
				(width 0.1524)
				(type default)
			)
			(layer "F.SilkS")
		)
		(fp_line
			(start 1.2954 -0.5842)
			(end 1.2954 0.5842)
			(stroke
				(width 0.1524)
				(type default)
			)
			(layer "F.SilkS")
		)
		(fp_line
			(start -0.8636 0.4572)
			(end -0.8636 0.4064)
			(stroke
				(width 0.1)
				(type default)
			)
			(layer "F.Fab")
		)
		(fp_line
			(start 0.8636 0.4572)
			(end -0.8636 0.4572)
			(stroke
				(width 0.1)
				(type default)
			)
			(layer "F.Fab")
		)
		(fp_line
			(start -1.1938 0.4064)
			(end -1.1938 -0.4064)
			(stroke
				(width 0.1)
				(type default)
			)
			(layer "F.Fab")
		)
		(fp_line
			(start -0.8636 0.4064)
			(end -1.1938 0.4064)
			(stroke
				(width 0.1)
				(type default)
			)
			(layer "F.Fab")
		)
		(fp_line
			(start 0.8636 0.4064)
			(end 0.8636 0.4572)
			(stroke
				(width 0.1)
				(type default)
			)
			(layer "F.Fab")
		)
		(fp_line
			(start 1.1938 0.4064)
			(end 0.8636 0.4064)
			(stroke
				(width 0.1)
				(type default)
			)
			(layer "F.Fab")
		)
		(fp_line
			(start -1.1938 -0.4064)
			(end -0.8636 -0.4064)
			(stroke
				(width 0.1)
				(type default)
			)
			(layer "F.Fab")
		)
		(fp_line
			(start -0.8636 -0.4064)
			(end -0.8636 -0.4572)
			(stroke
				(width 0.1)
				(type default)
			)
			(layer "F.Fab")
		)
		(fp_line
			(start 0.8636 -0.4064)
			(end 1.1938 -0.4064)
			(stroke
				(width 0.1)
				(type default)
			)
			(layer "F.Fab")
		)
		(fp_line
			(start 1.1938 -0.4064)
			(end 1.1938 0.4064)
			(stroke
				(width 0.1)
				(type default)
			)
			(layer "F.Fab")
		)
		(fp_line
			(start -0.8636 -0.4572)
			(end 0.8636 -0.4572)
			(stroke
				(width 0.1)
				(type default)
			)
			(layer "F.Fab")
		)
		(fp_line
			(start 0.8636 -0.4572)
			(end 0.8636 -0.4064)
			(stroke
				(width 0.1)
				(type default)
			)
			(layer "F.Fab")
		)
		(pad "1" smd rect
			(at -0.7366 0 180)
			(size 0.7112 0.8128)
			(layers "F.Cu" "F.Mask" "F.Paste")
			(net "P1V8_PLL0_PEX1")
		)
		(pad "2" smd rect
			(at 0.7366 0 180)
			(size 0.7112 0.8128)
			(layers "F.Cu" "F.Mask" "F.Paste")
			(net "GND")
		)
	)
	(footprint ""
		(layer "F.Cu")
		(at 454.961752 -49.918874)
		(property "Reference" "R1768"
			(at 0 0 0)
			(layer "F.SilkS")
			(hide yes)
			(effects
				(font
					(size 1.27 1.27)
				)
			)
		)
		(property "Value" ""
			(at 0 0 0)
			(layer "F.Fab")
			(effects
				(font
					(size 1.27 1.27)
				)
			)
		)
		(duplicate_pad_numbers_are_jumpers no)
		(fp_line
			(start -0.7874 -0.4064)
			(end 0.7874 -0.4064)
			(stroke
				(width 0.1524)
				(type default)
			)
			(layer "F.SilkS")
		)
		(fp_line
			(start -0.7874 0.4064)
			(end -0.7874 -0.4064)
			(stroke
				(width 0.1524)
				(type default)
			)
			(layer "F.SilkS")
		)
		(fp_line
			(start 0.7874 -0.4064)
			(end 0.7874 0.4064)
			(stroke
				(width 0.1524)
				(type default)
			)
			(layer "F.SilkS")
		)
		(fp_line
			(start 0.7874 0.4064)
			(end -0.7874 0.4064)
			(stroke
				(width 0.1524)
				(type default)
			)
			(layer "F.SilkS")
		)
		(fp_line
			(start -0.67945 -0.305054)
			(end -0.12065 -0.305054)
			(stroke
				(width 0.1)
				(type default)
			)
			(layer "F.Fab")
		)
		(fp_line
			(start -0.67945 0.3048)
			(end -0.67945 -0.305054)
			(stroke
				(width 0.1)
				(type default)
			)
			(layer "F.Fab")
		)
		(fp_line
			(start -0.12065 -0.305054)
			(end -0.12065 -0.2794)
			(stroke
				(width 0.1)
				(type default)
			)
			(layer "F.Fab")
		)
		(fp_line
			(start -0.12065 -0.2794)
			(end 0.12065 -0.2794)
			(stroke
				(width 0.1)
				(type default)
			)
			(layer "F.Fab")
		)
		(fp_line
			(start -0.12065 0.2794)
			(end -0.12065 0.3048)
			(stroke
				(width 0.1)
				(type default)
			)
			(layer "F.Fab")
		)
		(fp_line
			(start -0.12065 0.3048)
			(end -0.67945 0.3048)
			(stroke
				(width 0.1)
				(type default)
			)
			(layer "F.Fab")
		)
		(fp_line
			(start 0.120396 0.2794)
			(end -0.12065 0.2794)
			(stroke
				(width 0.1)
				(type default)
			)
			(layer "F.Fab")
		)
		(fp_line
			(start 0.120396 0.3048)
			(end 0.120396 0.2794)
			(stroke
				(width 0.1)
				(type default)
			)
			(layer "F.Fab")
		)
		(fp_line
			(start 0.12065 -0.3048)
			(end 0.67945 -0.3048)
			(stroke
				(width 0.1)
				(type default)
			)
			(layer "F.Fab")
		)
		(fp_line
			(start 0.12065 -0.2794)
			(end 0.12065 -0.3048)
			(stroke
				(width 0.1)
				(type default)
			)
			(layer "F.Fab")
		)
		(fp_line
			(start 0.67945 -0.3048)
			(end 0.67945 0.3048)
			(stroke
				(width 0.1)
				(type default)
			)
			(layer "F.Fab")
		)
		(fp_line
			(start 0.67945 0.3048)
			(end 0.120396 0.3048)
			(stroke
				(width 0.1)
				(type default)
			)
			(layer "F.Fab")
		)
		(pad "1" smd circle
			(at -0.40005 0)
			(size 0 0)
			(layers "F.Cu" "F.Mask" "F.Paste")
			(net "SMB_BIC_I2C6_MUX_SSD_8_15_ADC_R_SCL")
		)
		(pad "2" smd circle
			(at 0.40005 0)
			(size 0 0)
			(layers "F.Cu" "F.Mask" "F.Paste")
			(net "SMB_BIC_I2C6_MUX_SSD_8_15_ADC_SCL")
		)
	)
)
